(kicad_pcb
	(version 20241229)
	(generator "pcbnew")
	(generator_version "9.0")
	(general
		(thickness 1.61)
		(legacy_teardrops no)
	)
	(paper "A3")
	(title_block
		(title "RDIMM DDR5 Tester")
		(date "2026-05-21")
		(rev "2.2.0")
		(company "Antmicro")
		(comment 9 "footprints 367-371 of 796")
	)
	(layers
		(0 "F.Cu" signal)
		(4 "In1.Cu" power)
		(6 "In2.Cu" mixed)
		(8 "In3.Cu" power)
		(10 "In4.Cu" mixed)
		(12 "In5.Cu" power)
		(14 "In6.Cu" mixed)
		(16 "In7.Cu" power)
		(18 "In8.Cu" power)
		(20 "In9.Cu" mixed)
		(22 "In10.Cu" power)
		(2 "B.Cu" signal)
		(9 "F.Adhes" user "F.Adhesive")
		(11 "B.Adhes" user "B.Adhesive")
		(13 "F.Paste" user)
		(15 "B.Paste" user)
		(5 "F.SilkS" user "F.Silkscreen")
		(7 "B.SilkS" user "B.Silkscreen")
		(1 "F.Mask" user)
		(3 "B.Mask" user)
		(17 "Dwgs.User" user "User.Drawings")
		(19 "Cmts.User" user "User.Comments")
		(21 "Eco1.User" user "User.Eco1")
		(23 "Eco2.User" user "User.Eco2")
		(25 "Edge.Cuts" user)
		(27 "Margin" user)
		(31 "F.CrtYd" user "F.Courtyard")
		(29 "B.CrtYd" user "B.Courtyard")
		(35 "F.Fab" user)
		(33 "B.Fab" user)
	)
	(footprint "antmicro-footprints:SOD-523"
		(layer "F.Cu")
		(at 147.7745 172.934 180)
		(property "Reference" "D15"
			(at -1.1455 -1.816 0)
			(layer "F.SilkS")
			(effects
				(font
					(size 0.7 0.7)
					(thickness 0.15)
				)
				(justify right bottom)
			)
		)
		(property "Value" "BAT54-02V-G3-08"
			(at 0 1.499 0)
			(layer "F.Fab")
			(effects
				(font
					(size 0.7 0.7)
					(thickness 0.15)
				)
				(justify right bottom)
			)
		)
		(property "Datasheet" "https://www.vishay.com/docs/85633/bat5402v.pdf"
			(at 0 0 180)
			(layer "F.Fab")
			(hide yes)
			(effects
				(font
					(size 1.27 1.27)
					(thickness 0.15)
				)
			)
		)
		(property "MPN" "BAT54-02V-G3-08"
			(at 0 0 180)
			(unlocked yes)
			(layer "F.Fab")
			(hide yes)
			(effects
				(font
					(size 1 1)
					(thickness 0.15)
				)
			)
		)
		(property "Manufacturer" "Vishay"
			(at 0 0 180)
			(unlocked yes)
			(layer "F.Fab")
			(hide yes)
			(effects
				(font
					(size 1 1)
					(thickness 0.15)
				)
			)
		)
		(property "Author" "Antmicro"
			(at 0 0 180)
			(unlocked yes)
			(layer "F.Fab")
			(hide yes)
			(effects
				(font
					(size 1 1)
					(thickness 0.15)
				)
			)
		)
		(property "License" "Apache-2.0"
			(at 0 0 180)
			(unlocked yes)
			(layer "F.Fab")
			(hide yes)
			(effects
				(font
					(size 1 1)
					(thickness 0.15)
				)
			)
		)
		(sheetname "/Debug FTDI + VNA/")
		(sheetfile "debug-ftdi.kicad_sch")
		(attr smd)
		(fp_line
			(start -0.35 -0.5)
			(end -0.35 0.5)
			(stroke
				(width 0.15)
				(type solid)
			)
			(layer "F.SilkS")
		)
		(fp_rect
			(start -1 -0.6)
			(end 1 0.6)
			(stroke
				(width 0.05)
				(type solid)
			)
			(fill no)
			(layer "F.CrtYd")
		)
		(fp_line
			(start 0.65 -0.425)
			(end 0.65 0.423)
			(stroke
				(width 0.15)
				(type solid)
			)
			(layer "F.Fab")
		)
		(fp_line
			(start -0.35 -0.4)
			(end -0.35 0.4)
			(stroke
				(width 0.15)
				(type solid)
			)
			(layer "F.Fab")
		)
		(fp_line
			(start -0.652 0.423)
			(end 0.65 0.423)
			(stroke
				(width 0.15)
				(type solid)
			)
			(layer "F.Fab")
		)
		(fp_line
			(start -0.652 0.423)
			(end -0.652 -0.425)
			(stroke
				(width 0.15)
				(type solid)
			)
			(layer "F.Fab")
		)
		(fp_line
			(start -0.652 -0.425)
			(end 0.65 -0.425)
			(stroke
				(width 0.15)
				(type solid)
			)
			(layer "F.Fab")
		)
		(fp_text user "${REFERENCE}"
			(at -1.276 3.499 180)
			(layer "F.Fab")
			(effects
				(font
					(size 0.7 0.7)
					(thickness 0.15)
				)
				(justify left bottom)
			)
		)
		(fp_text user "License: Apache-2.0"
			(at -1.276 5.9 180)
			(layer "F.Fab")
			(effects
				(font
					(size 0.7 0.7)
					(thickness 0.15)
				)
				(justify left bottom)
			)
		)
		(fp_text user "Author: Antmicro"
			(at -1.276 4.7 180)
			(layer "F.Fab")
			(effects
				(font
					(size 0.7 0.7)
					(thickness 0.15)
				)
				(justify left bottom)
			)
		)
		(pad "1" smd roundrect
			(at -0.701 0 180)
			(size 0.5 0.6)
			(layers "F.Cu" "F.Mask" "F.Paste")
			(roundrect_rratio 0.25)
			(net 44 "/Debug FTDI + VNA/FTDI_SDA_OUT")
			(pinfunction "C")
			(pintype "passive")
		)
		(pad "2" smd roundrect
			(at 0.699 0 180)
			(size 0.5 0.6)
			(layers "F.Cu" "F.Mask" "F.Paste")
			(roundrect_rratio 0.25)
			(net 139 "/Debug FTDI + VNA/FTDI_SDA_IN")
			(pinfunction "A")
			(pintype "passive")
		)
	)
	(footprint "antmicro-footprints:L_WE-HCM-7050"
		(layer "F.Cu")
		(at 218.91 174.72 90)
		(property "Reference" "L1"
			(at -2.9 -3.9 90)
			(layer "F.SilkS")
			(effects
				(font
					(size 0.7 0.7)
					(thickness 0.15)
				)
				(justify left bottom)
			)
		)
		(property "Value" "L_150n_30A_WE-HCM-7050"
			(at -2.9 5.2 90)
			(layer "F.Fab")
			(effects
				(font
					(size 0.7 0.7)
					(thickness 0.15)
				)
				(justify left bottom)
			)
		)
		(property "Datasheet" "https://www.we-online.com/components/products/datasheet/744302015.pdf"
			(at 0 0 90)
			(layer "F.Fab")
			(hide yes)
			(effects
				(font
					(size 1.27 1.27)
					(thickness 0.15)
				)
			)
		)
		(property "Val" "150n/30A"
			(at 0 0 90)
			(unlocked yes)
			(layer "F.Fab")
			(hide yes)
			(effects
				(font
					(size 1 1)
					(thickness 0.15)
				)
			)
		)
		(property "Manufacturer" "Würth Elektronik"
			(at 0 0 90)
			(unlocked yes)
			(layer "F.Fab")
			(hide yes)
			(effects
				(font
					(size 1 1)
					(thickness 0.15)
				)
			)
		)
		(property "MPN" "744302015"
			(at 0 0 90)
			(unlocked yes)
			(layer "F.Fab")
			(hide yes)
			(effects
				(font
					(size 1 1)
					(thickness 0.15)
				)
			)
		)
		(property "ISat" "35 A"
			(at 0 0 90)
			(unlocked yes)
			(layer "F.Fab")
			(hide yes)
			(effects
				(font
					(size 1 1)
					(thickness 0.15)
				)
			)
		)
		(property "IMax" "30 A"
			(at 0 0 90)
			(unlocked yes)
			(layer "F.Fab")
			(hide yes)
			(effects
				(font
					(size 1 1)
					(thickness 0.15)
				)
			)
		)
		(property "Size" "7.15x7"
			(at 0 0 90)
			(unlocked yes)
			(layer "F.Fab")
			(hide yes)
			(effects
				(font
					(size 1 1)
					(thickness 0.15)
				)
			)
		)
		(property "Author" "Antmicro"
			(at 0 0 90)
			(unlocked yes)
			(layer "F.Fab")
			(hide yes)
			(effects
				(font
					(size 1 1)
					(thickness 0.15)
				)
			)
		)
		(property "License" "Apache-2.0"
			(at 0 0 90)
			(unlocked yes)
			(layer "F.Fab")
			(hide yes)
			(effects
				(font
					(size 1 1)
					(thickness 0.15)
				)
			)
		)
		(sheetname "/Supply/DC-DC VCCINT/")
		(sheetfile "dc-dc-vccint.kicad_sch")
		(attr smd)
		(fp_line
			(start 3.6 -3.6)
			(end -3.6 -3.6)
			(stroke
				(width 0.15)
				(type solid)
			)
			(layer "F.SilkS")
		)
		(fp_line
			(start -3.6 -3.6)
			(end -3.6 -1.8)
			(stroke
				(width 0.15)
				(type solid)
			)
			(layer "F.SilkS")
		)
		(fp_line
			(start 3.6 -1.8)
			(end 3.6 -3.6)
			(stroke
				(width 0.15)
				(type solid)
			)
			(layer "F.SilkS")
		)
		(fp_line
			(start 3.6 1.8)
			(end 3.6 3.6)
			(stroke
				(width 0.15)
				(type solid)
			)
			(layer "F.SilkS")
		)
		(fp_line
			(start -3.6 1.8)
			(end -3.6 3.6)
			(stroke
				(width 0.15)
				(type solid)
			)
			(layer "F.SilkS")
		)
		(fp_line
			(start 3.6 3.6)
			(end -3.6 3.6)
			(stroke
				(width 0.15)
				(type solid)
			)
			(layer "F.SilkS")
		)
		(fp_rect
			(start -3.9 -3.75)
			(end 3.9 3.75)
			(stroke
				(width 0.05)
				(type solid)
			)
			(fill no)
			(layer "F.CrtYd")
		)
		(fp_rect
			(start -3.5 -3.5)
			(end 3.5 3.5)
			(stroke
				(width 0.15)
				(type solid)
			)
			(fill no)
			(layer "F.Fab")
		)
		(fp_text user "${REFERENCE}"
			(at -4.25 7.2 90)
			(layer "F.Fab")
			(effects
				(font
					(size 0.7 0.7)
					(thickness 0.15)
				)
				(justify left bottom)
			)
		)
		(fp_text user "License: Apache-2.0"
			(at -4.25 8.4 90)
			(layer "F.Fab")
			(effects
				(font
					(size 0.7 0.7)
					(thickness 0.15)
				)
				(justify left bottom)
			)
		)
		(fp_text user "Author: Antmicro"
			(at -4.25 9.6 90)
			(layer "F.Fab")
			(effects
				(font
					(size 0.7 0.7)
					(thickness 0.15)
				)
				(justify left bottom)
			)
		)
		(pad "1" smd roundrect
			(at -2.65 0 90)
			(size 2 3.05)
			(layers "F.Cu" "F.Mask" "F.Paste")
			(roundrect_rratio 0.1)
			(net 165 "Net-(C215-Pad2)")
			(pintype "passive")
		)
		(pad "2" smd roundrect
			(at 2.65 0 270)
			(size 2 3.05)
			(layers "F.Cu" "F.Mask" "F.Paste")
			(roundrect_rratio 0.1)
			(net 223 "/Supply/DC-DC VCCINT/0V85_REG0")
			(pintype "passive")
		)
	)
	(footprint "antmicro-footprints:R_0402_1005Metric"
		(layer "F.Cu")
		(at 119.15 152.61 180)
		(descr "Resistor SMD 0402")
		(tags "resistor SMD 0402")
		(property "Reference" "R33"
			(at -5.11 -0.415 180)
			(layer "F.SilkS")
			(effects
				(font
					(size 0.7 0.7)
					(thickness 0.15)
				)
				(justify right bottom)
			)
		)
		(property "Value" "R_49k9_0402"
			(at -1.011843 1.772047 0)
			(layer "F.Fab")
			(effects
				(font
					(size 0.7 0.7)
					(thickness 0.15)
				)
				(justify right bottom)
			)
		)
		(property "Datasheet" "https://www.bourns.com/docs/product-datasheets/cr.pdf"
			(at 0 0 180)
			(layer "F.Fab")
			(hide yes)
			(effects
				(font
					(size 1.27 1.27)
					(thickness 0.15)
				)
			)
		)
		(property "MPN" "CR0402-FX-4992GLF"
			(at 0 0 180)
			(unlocked yes)
			(layer "F.Fab")
			(hide yes)
			(effects
				(font
					(size 1 1)
					(thickness 0.15)
				)
			)
		)
		(property "Manufacturer" "Bourns"
			(at 0 0 180)
			(unlocked yes)
			(layer "F.Fab")
			(hide yes)
			(effects
				(font
					(size 1 1)
					(thickness 0.15)
				)
			)
		)
		(property "License" "Apache-2.0"
			(at 0 0 180)
			(unlocked yes)
			(layer "F.Fab")
			(hide yes)
			(effects
				(font
					(size 1 1)
					(thickness 0.15)
				)
			)
		)
		(property "Author" "Antmicro"
			(at 0 0 180)
			(unlocked yes)
			(layer "F.Fab")
			(hide yes)
			(effects
				(font
					(size 1 1)
					(thickness 0.15)
				)
			)
		)
		(property "Val" "49k9"
			(at 0 0 180)
			(unlocked yes)
			(layer "F.Fab")
			(hide yes)
			(effects
				(font
					(size 1 1)
					(thickness 0.15)
				)
			)
		)
		(property "Tolerance" "1%"
			(at 0 0 180)
			(unlocked yes)
			(layer "F.Fab")
			(hide yes)
			(effects
				(font
					(size 1 1)
					(thickness 0.15)
				)
			)
		)
		(sheetname "/HDMI + SD Card/")
		(sheetfile "hdmi-sd-card.kicad_sch")
		(attr smd)
		(fp_rect
			(start -0.925 -0.47)
			(end 0.925 0.47)
			(stroke
				(width 0.05)
				(type default)
			)
			(fill no)
			(layer "F.CrtYd")
		)
		(fp_rect
			(start -0.5 -0.25)
			(end 0.5 0.25)
			(stroke
				(width 0.15)
				(type solid)
			)
			(fill no)
			(layer "F.Fab")
		)
		(fp_text user "Author: Antmicro"
			(at -0.95 4.169 180)
			(layer "F.Fab")
			(effects
				(font
					(size 0.7 0.7)
					(thickness 0.15)
				)
				(justify left bottom)
			)
		)
		(fp_text user "License: Apache-2.0"
			(at -0.95 5.169 180)
			(layer "F.Fab")
			(effects
				(font
					(size 0.7 0.7)
					(thickness 0.15)
				)
				(justify left bottom)
			)
		)
		(fp_text user "${REFERENCE}"
			(at -0.95 3.168 180)
			(layer "F.Fab")
			(effects
				(font
					(size 0.7 0.7)
					(thickness 0.15)
				)
				(justify left bottom)
			)
		)
		(pad "1" smd roundrect
			(at -0.48 0 180)
			(size 0.59 0.64)
			(layers "F.Cu" "F.Mask" "F.Paste")
			(roundrect_rratio 0.25)
			(net 679 "Net-(L9-Pad2)")
			(pintype "passive")
		)
		(pad "2" smd roundrect
			(at 0.48 0 180)
			(size 0.59 0.64)
			(layers "F.Cu" "F.Mask" "F.Paste")
			(roundrect_rratio 0.25)
			(net 322 "Net-(C300-Pad2)")
			(pintype "passive")
		)
	)
	(footprint "antmicro-footprints:C_0603_1608Metric"
		(layer "F.Cu")
		(at 226.635 168.755)
		(descr "Capacitor SMD 0603")
		(tags "capacitor 0603")
		(property "Reference" "C271"
			(at -1.36 -2.155 0)
			(layer "F.SilkS")
			(effects
				(font
					(size 0.7 0.7)
					(thickness 0.15)
				)
				(justify left bottom)
			)
		)
		(property "Value" "C_22u_0603"
			(at -1.42757 1.770288 0)
			(layer "F.Fab")
			(effects
				(font
					(size 0.7 0.7)
					(thickness 0.15)
				)
				(justify left bottom)
			)
		)
		(property "Datasheet" "https://www.murata.com/products/productdetail?partno=GRM188R60J226MEA0%23"
			(at 0 0 0)
			(layer "F.Fab")
			(hide yes)
			(effects
				(font
					(size 1.27 1.27)
					(thickness 0.15)
				)
			)
		)
		(property "Manufacturer" "Murata"
			(at 0 0 0)
			(unlocked yes)
			(layer "F.Fab")
			(hide yes)
			(effects
				(font
					(size 1 1)
					(thickness 0.15)
				)
			)
		)
		(property "MPN" "GRM188R60J226MEA0D"
			(at 0 0 0)
			(unlocked yes)
			(layer "F.Fab")
			(hide yes)
			(effects
				(font
					(size 1 1)
					(thickness 0.15)
				)
			)
		)
		(property "Val" "22u"
			(at 0 0 0)
			(unlocked yes)
			(layer "F.Fab")
			(hide yes)
			(effects
				(font
					(size 1 1)
					(thickness 0.15)
				)
			)
		)
		(property "License" "Apache-2.0"
			(at 0 0 0)
			(unlocked yes)
			(layer "F.Fab")
			(hide yes)
			(effects
				(font
					(size 1 1)
					(thickness 0.15)
				)
			)
		)
		(property "Author" "Antmicro"
			(at 0 0 0)
			(unlocked yes)
			(layer "F.Fab")
			(hide yes)
			(effects
				(font
					(size 1 1)
					(thickness 0.15)
				)
			)
		)
		(property "Voltage" ""
			(at 0 0 0)
			(unlocked yes)
			(layer "F.Fab")
			(hide yes)
			(effects
				(font
					(size 1 1)
					(thickness 0.15)
				)
			)
		)
		(property "Dielectric" ""
			(at 0 0 0)
			(unlocked yes)
			(layer "F.Fab")
			(hide yes)
			(effects
				(font
					(size 1 1)
					(thickness 0.15)
				)
			)
		)
		(sheetname "/Supply/DC-DC VCCINT/")
		(sheetfile "dc-dc-vccint.kicad_sch")
		(attr smd)
		(fp_line
			(start -0.15 -0.4)
			(end 0.15 -0.4)
			(stroke
				(width 0.15)
				(type solid)
			)
			(layer "F.SilkS")
		)
		(fp_line
			(start -0.15 0.4)
			(end 0.15 0.4)
			(stroke
				(width 0.15)
				(type solid)
			)
			(layer "F.SilkS")
		)
		(fp_rect
			(start -1.25 -0.65)
			(end 1.25 0.65)
			(stroke
				(width 0.05)
				(type solid)
			)
			(fill no)
			(layer "F.CrtYd")
		)
		(fp_rect
			(start -0.8 -0.4)
			(end 0.8 0.4)
			(stroke
				(width 0.15)
				(type solid)
			)
			(fill no)
			(layer "F.Fab")
		)
		(fp_text user "Author: Antmicro"
			(at -1.682 4.894 0)
			(layer "F.Fab")
			(effects
				(font
					(size 0.7 0.7)
					(thickness 0.15)
				)
				(justify left bottom)
			)
		)
		(fp_text user "${REFERENCE}"
			(at -1.682 3.895 0)
			(layer "F.Fab")
			(effects
				(font
					(size 0.7 0.7)
					(thickness 0.15)
				)
				(justify left bottom)
			)
		)
		(fp_text user "License: Apache-2.0"
			(at -1.682 5.895 0)
			(layer "F.Fab")
			(effects
				(font
					(size 0.7 0.7)
					(thickness 0.15)
				)
				(justify left bottom)
			)
		)
		(pad "1" smd roundrect
			(at -0.7 0)
			(size 0.8 1)
			(layers "F.Cu" "F.Mask" "F.Paste")
			(roundrect_rratio 0.2)
			(net 1 "GND")
			(pintype "passive")
		)
		(pad "2" smd roundrect
			(at 0.7 0)
			(size 0.8 1)
			(layers "F.Cu" "F.Mask" "F.Paste")
			(roundrect_rratio 0.2)
			(net 224 "/Supply/DC-DC VCCINT/0V85_REG1")
			(pintype "passive")
		)
	)
	(footprint "antmicro-footprints:SC70-3"
		(layer "F.Cu")
		(at 234.35 166.2 90)
		(property "Reference" "Q15"
			(at -0.35 -1.1 180)
			(layer "F.SilkS")
			(effects
				(font
					(size 0.7 0.7)
					(thickness 0.15)
				)
				(justify left bottom)
			)
		)
		(property "Value" "BSS138PW"
			(at -74.770501 -11.8455 90)
			(layer "F.Fab")
			(effects
				(font
					(size 0.7 0.7)
					(thickness 0.15)
				)
				(justify left bottom)
			)
		)
		(property "Datasheet" "https://assets.nexperia.com/documents/data-sheet/BSS138PW.pdf"
			(at 0 0 90)
			(layer "F.Fab")
			(hide yes)
			(effects
				(font
					(size 1.27 1.27)
					(thickness 0.15)
				)
			)
		)
		(property "MPN" "BSS138PW"
			(at 0 0 90)
			(unlocked yes)
			(layer "F.Fab")
			(hide yes)
			(effects
				(font
					(size 1 1)
					(thickness 0.15)
				)
			)
		)
		(property "Manufacturer" "Nexperia"
			(at 0 0 90)
			(unlocked yes)
			(layer "F.Fab")
			(hide yes)
			(effects
				(font
					(size 1 1)
					(thickness 0.15)
				)
			)
		)
		(property "Author" "Antmicro"
			(at 0 0 90)
			(unlocked yes)
			(layer "F.Fab")
			(hide yes)
			(effects
				(font
					(size 1 1)
					(thickness 0.15)
				)
			)
		)
		(property "License" "Apache-2.0"
			(at 0 0 90)
			(unlocked yes)
			(layer "F.Fab")
			(hide yes)
			(effects
				(font
					(size 1 1)
					(thickness 0.15)
				)
			)
		)
		(sheetname "/Supply/")
		(sheetfile "supply.kicad_sch")
		(attr smd)
		(fp_line
			(start -0.3 -1)
			(end 0.627 -0.999)
			(stroke
				(width 0.15)
				(type solid)
			)
			(layer "F.SilkS")
		)
		(fp_line
			(start 0.627 -0.6)
			(end 0.627 -0.999)
			(stroke
				(width 0.15)
				(type solid)
			)
			(layer "F.SilkS")
		)
		(fp_line
			(start 0.627 0.6)
			(end 0.627 1.001)
			(stroke
				(width 0.15)
				(type solid)
			)
			(layer "F.SilkS")
		)
		(fp_line
			(start -0.3 1)
			(end 0.627 1.001)
			(stroke
				(width 0.15)
				(type solid)
			)
			(layer "F.SilkS")
		)
		(fp_line
			(start 0.9 -1.3)
			(end 0.9 -0.4)
			(stroke
				(width 0.05)
				(type solid)
			)
			(layer "F.CrtYd")
		)
		(fp_line
			(start -0.9 -1.3)
			(end 0.9 -1.3)
			(stroke
				(width 0.05)
				(type solid)
			)
			(layer "F.CrtYd")
		)
		(fp_line
			(start -0.9 -1.3)
			(end -0.9 -1)
			(stroke
				(width 0.05)
				(type solid)
			)
			(layer "F.CrtYd")
		)
		(fp_line
			(start -0.9 -1)
			(end -1.4 -1)
			(stroke
				(width 0.05)
				(type solid)
			)
			(layer "F.CrtYd")
		)
		(fp_line
			(start 1.4 -0.4)
			(end 1.4 0.4)
			(stroke
				(width 0.05)
				(type solid)
			)
			(layer "F.CrtYd")
		)
		(fp_line
			(start 0.9 -0.4)
			(end 1.4 -0.4)
			(stroke
				(width 0.05)
				(type solid)
			)
			(layer "F.CrtYd")
		)
		(fp_line
			(start 1.4 0.4)
			(end 0.9 0.4)
			(stroke
				(width 0.05)
				(type solid)
			)
			(layer "F.CrtYd")
		)
		(fp_line
			(start 0.9 0.4)
			(end 0.9 1.3)
			(stroke
				(width 0.05)
				(type solid)
			)
			(layer "F.CrtYd")
		)
		(fp_line
			(start -0.9 1)
			(end -1.4 1)
			(stroke
				(width 0.05)
				(type solid)
			)
			(layer "F.CrtYd")
		)
		(fp_line
			(start -1.4 1)
			(end -1.4 -1)
			(stroke
				(width 0.05)
				(type solid)
			)
			(layer "F.CrtYd")
		)
		(fp_line
			(start 0.9 1.3)
			(end -0.9 1.3)
			(stroke
				(width 0.05)
				(type solid)
			)
			(layer "F.CrtYd")
		)
		(fp_line
			(start -0.9 1.3)
			(end -0.9 1)
			(stroke
				(width 0.05)
				(type solid)
			)
			(layer "F.CrtYd")
		)
		(fp_rect
			(start -0.623 -0.999)
			(end 0.627 1.001)
			(stroke
				(width 0.15)
				(type solid)
			)
			(fill no)
			(layer "F.Fab")
		)
		(fp_text user "${REFERENCE}"
			(at -1.45 4.783 90)
			(layer "F.Fab")
			(effects
				(font
					(size 0.7 0.7)
					(thickness 0.15)
				)
				(justify left bottom)
			)
		)
		(fp_text user "License: Apache-2.0"
			(at -1.45 6.782 90)
			(layer "F.Fab")
			(effects
				(font
					(size 0.7 0.7)
					(thickness 0.15)
				)
				(justify left bottom)
			)
		)
		(fp_text user "Author: Antmicro"
			(at -1.45 5.782 90)
			(layer "F.Fab")
			(effects
				(font
					(size 0.7 0.7)
					(thickness 0.15)
				)
				(justify left bottom)
			)
		)
		(pad "1" smd rect
			(at -1.051 -0.65 180)
			(size 0.6 0.6)
			(layers "F.Cu" "F.Mask" "F.Paste")
			(net 206 "FAN_PWM")
			(pinfunction "G")
			(pintype "passive")
		)
		(pad "2" smd rect
			(at -1.051 0.65 180)
			(size 0.6 0.6)
			(layers "F.Cu" "F.Mask" "F.Paste")
			(net 1 "GND")
			(pinfunction "S")
			(pintype "passive")
		)
		(pad "3" smd rect
			(at 1.05 0 180)
			(size 0.6 0.6)
			(layers "F.Cu" "F.Mask" "F.Paste")
			(net 250 "Net-(Q15-D)")
			(pinfunction "D")
			(pintype "passive")
		)
	)
)
